# S9S_MB_2U (Grand Teton) — schematic netlist excerpt (pin names and nets, part order shuffled) for the footprints in the layout excerpt that follows; sources: Cadence DE-HDL packaged netlist, KiCad conversion of 03242023_DA0F0TMBIJ0_F0T_Motherboard_J_brd_V01_OCP.brd

R4576  Q_RES  0 5% EMPTY  pkg 0402LF  page 146 : A = GPU_3V3IO_RSVD5_FFU ; B = GPU_3V3IO_RSVD5_FFU_ISO
PL210  Q_INDUCTOR  130NH/106A IND  pkg SMLF  page 272 : \1\ = SW_PVCCFA_EHV_FIVRA_CPU0_SW4 ; \2\ = PVCCFA_EHV_FIVRA_CPU0

(kicad_pcb
	(version 20260206)
	(generator "pcbnew")
	(generator_version "10.0")
	(general
		(thickness 1.6)
		(legacy_teardrops no)
	)
	(paper "A4")
	(title_block
		(title "03242023_DA0F0TMBIJ0_F0T_Motherboard_J_brd_V01_OCP.brd")
		(comment 1 "Grand Teton / footprints 3375-3376 of 6105")
	)
	(layers
		(0 "F.Cu" signal "TOP")
		(4 "In1.Cu" signal "GND")
		(6 "In2.Cu" signal "IN1")
		(8 "In3.Cu" signal "GND1")
		(10 "In4.Cu" signal "IN2")
		(12 "In5.Cu" signal "GND2")
		(14 "In6.Cu" signal "IN3")
		(16 "In7.Cu" signal "GND3")
		(18 "In8.Cu" signal "VCC")
		(20 "In9.Cu" signal "VCC1")
		(22 "In10.Cu" signal "GND4")
		(24 "In11.Cu" signal "IN4")
		(26 "In12.Cu" signal "GND5")
		(28 "In13.Cu" signal "IN5")
		(30 "In14.Cu" signal "GND6")
		(32 "In15.Cu" signal "IN6")
		(34 "In16.Cu" signal "GND7")
		(2 "B.Cu" signal "BOTTOM")
		(9 "F.Adhes" user "F.Adhesive")
		(11 "B.Adhes" user "B.Adhesive")
		(13 "F.Paste" user "Package Geometry/Pastemask Top")
		(15 "B.Paste" user "Package Geometry/Pastemask Bottom")
		(5 "F.SilkS" user "Ref Des/Silkscreen Top")
		(7 "B.SilkS" user "Ref Des/Silkscreen Bottom")
		(1 "F.Mask" user "Board Geometry/Soldermask Top")
		(3 "B.Mask" user "Board Geometry/Soldermask Bottom")
		(17 "Dwgs.User" user "User.Drawings")
		(19 "Cmts.User" user "User.Comments")
		(21 "Eco1.User" user "User.Eco1")
		(23 "Eco2.User" user "User.Eco2")
		(25 "Edge.Cuts" user "Board Geometry/Outline")
		(27 "Margin" user)
		(31 "F.CrtYd" user "Package Geometry/Place Bound Top")
		(29 "B.CrtYd" user "Package Geometry/Place Bound Bottom")
		(35 "F.Fab" user "Ref Des/Assembly Top")
		(33 "B.Fab" user "Ref Des/Assembly Bottom")
	)
	(footprint ""
		(layer "F.Cu")
		(at 288.794952 -354.000816 -90)
		(property "Reference" "PL210"
			(at -2.553462 8.124952 0)
			(unlocked yes)
			(layer "F.SilkS")
			(effects
				(font
					(size 0.7874 0.5842)
					(thickness 0.1524)
				)
				(justify left)
			)
		)
		(property "Value" ""
			(at 0 0 270)
			(layer "F.Fab")
			(effects
				(font
					(size 1.27 1.27)
				)
			)
		)
		(duplicate_pad_numbers_are_jumpers no)
		(fp_line
			(start -4.99999 3.750056)
			(end -4.99999 2.2479)
			(stroke
				(width 0.1524)
				(type default)
			)
			(layer "F.SilkS")
		)
		(fp_line
			(start 0 3.750056)
			(end -4.99999 3.750056)
			(stroke
				(width 0.1524)
				(type default)
			)
			(layer "F.SilkS")
		)
		(fp_line
			(start 4.99999 3.750056)
			(end 0 3.750056)
			(stroke
				(width 0.1524)
				(type default)
			)
			(layer "F.SilkS")
		)
		(fp_line
			(start 4.99999 2.2352)
			(end 4.99999 3.750056)
			(stroke
				(width 0.1524)
				(type default)
			)
			(layer "F.SilkS")
		)
		(fp_line
			(start -4.99999 -2.2479)
			(end -4.99999 -3.750056)
			(stroke
				(width 0.1524)
				(type default)
			)
			(layer "F.SilkS")
		)
		(fp_line
			(start -4.99999 -3.750056)
			(end 4.99999 -3.750056)
			(stroke
				(width 0.1524)
				(type default)
			)
			(layer "F.SilkS")
		)
		(fp_line
			(start 4.99999 -3.750056)
			(end 4.99999 -2.2479)
			(stroke
				(width 0.1524)
				(type default)
			)
			(layer "F.SilkS")
		)
		(fp_line
			(start -4.99999 3.750056)
			(end -4.99999 -3.750056)
			(stroke
				(width 0.1)
				(type default)
			)
			(layer "F.Fab")
		)
		(fp_line
			(start 0 3.750056)
			(end -4.99999 3.750056)
			(stroke
				(width 0.1)
				(type default)
			)
			(layer "F.Fab")
		)
		(fp_line
			(start 4.99999 3.750056)
			(end 0 3.750056)
			(stroke
				(width 0.1)
				(type default)
			)
			(layer "F.Fab")
		)
		(fp_line
			(start -4.99999 -3.750056)
			(end 4.99999 -3.750056)
			(stroke
				(width 0.1)
				(type default)
			)
			(layer "F.Fab")
		)
		(fp_line
			(start 4.99999 -3.750056)
			(end 4.99999 3.750056)
			(stroke
				(width 0.1)
				(type default)
			)
			(layer "F.Fab")
		)
		(pad "1" smd rect
			(at -3.299968 0 270)
			(size 3.302 4.2164)
			(layers "F.Cu" "F.Mask" "F.Paste")
			(net "SW_PVCCFA_EHV_FIVRA_CPU0_SW4")
		)
		(pad "2" smd rect
			(at 3.299968 0 270)
			(size 3.302 4.2164)
			(layers "F.Cu" "F.Mask" "F.Paste")
			(net "PVCCFA_EHV_FIVRA_CPU0")
		)
	)
	(footprint ""
		(layer "F.Cu")
		(at 298.04995 -417.2204)
		(property "Reference" "R4576"
			(at 0 0 0)
			(layer "F.SilkS")
			(hide yes)
			(effects
				(font
					(size 1.27 1.27)
				)
			)
		)
		(property "Value" ""
			(at 0 0 0)
			(layer "F.Fab")
			(effects
				(font
					(size 1.27 1.27)
				)
			)
		)
		(duplicate_pad_numbers_are_jumpers no)
		(fp_line
			(start -0.7874 -0.4064)
			(end 0.7874 -0.4064)
			(stroke
				(width 0.1524)
				(type default)
			)
			(layer "F.SilkS")
		)
		(fp_line
			(start -0.7874 0.4064)
			(end -0.7874 -0.4064)
			(stroke
				(width 0.1524)
				(type default)
			)
			(layer "F.SilkS")
		)
		(fp_line
			(start 0.7874 -0.4064)
			(end 0.7874 0.4064)
			(stroke
				(width 0.1524)
				(type default)
			)
			(layer "F.SilkS")
		)
		(fp_line
			(start 0.7874 0.4064)
			(end -0.7874 0.4064)
			(stroke
				(width 0.1524)
				(type default)
			)
			(layer "F.SilkS")
		)
		(fp_line
			(start -0.67945 -0.305054)
			(end -0.12065 -0.305054)
			(stroke
				(width 0.1)
				(type default)
			)
			(layer "F.Fab")
		)
		(fp_line
			(start -0.67945 0.3048)
			(end -0.67945 -0.305054)
			(stroke
				(width 0.1)
				(type default)
			)
			(layer "F.Fab")
		)
		(fp_line
			(start -0.12065 -0.305054)
			(end -0.12065 -0.2794)
			(stroke
				(width 0.1)
				(type default)
			)
			(layer "F.Fab")
		)
		(fp_line
			(start -0.12065 -0.2794)
			(end 0.12065 -0.2794)
			(stroke
				(width 0.1)
				(type default)
			)
			(layer "F.Fab")
		)
		(fp_line
			(start -0.12065 0.2794)
			(end -0.12065 0.3048)
			(stroke
				(width 0.1)
				(type default)
			)
			(layer "F.Fab")
		)
		(fp_line
			(start -0.12065 0.3048)
			(end -0.67945 0.3048)
			(stroke
				(width 0.1)
				(type default)
			)
			(layer "F.Fab")
		)
		(fp_line
			(start 0.120396 0.2794)
			(end -0.12065 0.2794)
			(stroke
				(width 0.1)
				(type default)
			)
			(layer "F.Fab")
		)
		(fp_line
			(start 0.120396 0.3048)
			(end 0.120396 0.2794)
			(stroke
				(width 0.1)
				(type default)
			)
			(layer "F.Fab")
		)
		(fp_line
			(start 0.12065 -0.3048)
			(end 0.67945 -0.3048)
			(stroke
				(width 0.1)
				(type default)
			)
			(layer "F.Fab")
		)
		(fp_line
			(start 0.12065 -0.2794)
			(end 0.12065 -0.3048)
			(stroke
				(width 0.1)
				(type default)
			)
			(layer "F.Fab")
		)
		(fp_line
			(start 0.67945 -0.3048)
			(end 0.67945 0.3048)
			(stroke
				(width 0.1)
				(type default)
			)
			(layer "F.Fab")
		)
		(fp_line
			(start 0.67945 0.3048)
			(end 0.120396 0.3048)
			(stroke
				(width 0.1)
				(type default)
			)
			(layer "F.Fab")
		)
		(pad "1" smd circle
			(at -0.40005 0)
			(size 0 0)
			(layers "F.Cu" "F.Mask" "F.Paste")
			(net "GPU_3V3IO_RSVD5_FFU")
		)
		(pad "2" smd circle
			(at 0.40005 0)
			(size 0 0)
			(layers "F.Cu" "F.Mask" "F.Paste")
			(net "GPU_3V3IO_RSVD5_FFU_ISO")
		)
	)
)
